# S9S_MB_2U (Grand Teton) — schematic netlist excerpt (pin names and nets, part order shuffled) for the footprints in the layout excerpt that follows; sources: Cadence DE-HDL packaged netlist, KiCad conversion of 03242023_DA0F0TMBIJ0_F0T_Motherboard_J_brd_V01_OCP.brd

R2531  Q_RES  0 5% CHIP  pkg 0402LF  page 247 : A = MB0_P12V_STBY_PWRGD ; B = FM_P12V_HSC_EN_R

(kicad_pcb
	(version 20260206)
	(generator "pcbnew")
	(generator_version "10.0")
	(general
		(thickness 1.6)
		(legacy_teardrops no)
	)
	(paper "A4")
	(title_block
		(title "03242023_DA0F0TMBIJ0_F0T_Motherboard_J_brd_V01_OCP.brd")
		(comment 1 "Grand Teton / footprints 1250-1250 of 6105")
	)
	(layers
		(0 "F.Cu" signal "TOP")
		(4 "In1.Cu" signal "GND")
		(6 "In2.Cu" signal "IN1")
		(8 "In3.Cu" signal "GND1")
		(10 "In4.Cu" signal "IN2")
		(12 "In5.Cu" signal "GND2")
		(14 "In6.Cu" signal "IN3")
		(16 "In7.Cu" signal "GND3")
		(18 "In8.Cu" signal "VCC")
		(20 "In9.Cu" signal "VCC1")
		(22 "In10.Cu" signal "GND4")
		(24 "In11.Cu" signal "IN4")
		(26 "In12.Cu" signal "GND5")
		(28 "In13.Cu" signal "IN5")
		(30 "In14.Cu" signal "GND6")
		(32 "In15.Cu" signal "IN6")
		(34 "In16.Cu" signal "GND7")
		(2 "B.Cu" signal "BOTTOM")
		(9 "F.Adhes" user "F.Adhesive")
		(11 "B.Adhes" user "B.Adhesive")
		(13 "F.Paste" user "Package Geometry/Pastemask Top")
		(15 "B.Paste" user "Package Geometry/Pastemask Bottom")
		(5 "F.SilkS" user "Ref Des/Silkscreen Top")
		(7 "B.SilkS" user "Ref Des/Silkscreen Bottom")
		(1 "F.Mask" user "Board Geometry/Soldermask Top")
		(3 "B.Mask" user "Board Geometry/Soldermask Bottom")
		(17 "Dwgs.User" user "User.Drawings")
		(19 "Cmts.User" user "User.Comments")
		(21 "Eco1.User" user "User.Eco1")
		(23 "Eco2.User" user "User.Eco2")
		(25 "Edge.Cuts" user "Board Geometry/Outline")
		(27 "Margin" user)
		(31 "F.CrtYd" user "Package Geometry/Place Bound Top")
		(29 "B.CrtYd" user "Package Geometry/Place Bound Bottom")
		(35 "F.Fab" user "Ref Des/Assembly Top")
		(33 "B.Fab" user "Ref Des/Assembly Bottom")
	)
	(footprint ""
		(layer "F.Cu")
		(at 207.43418 -127.996188 90)
		(property "Reference" "R2531"
			(at 0 0 90)
			(layer "F.SilkS")
			(hide yes)
			(effects
				(font
					(size 1.27 1.27)
				)
			)
		)
		(property "Value" ""
			(at 0 0 90)
			(layer "F.Fab")
			(effects
				(font
					(size 1.27 1.27)
				)
			)
		)
		(duplicate_pad_numbers_are_jumpers no)
		(fp_line
			(start 0.7874 -0.4064)
			(end 0.7874 0.4064)
			(stroke
				(width 0.1524)
				(type default)
			)
			(layer "F.SilkS")
		)
		(fp_line
			(start -0.7874 -0.4064)
			(end 0.7874 -0.4064)
			(stroke
				(width 0.1524)
				(type default)
			)
			(layer "F.SilkS")
		)
		(fp_line
			(start 0.7874 0.4064)
			(end -0.7874 0.4064)
			(stroke
				(width 0.1524)
				(type default)
			)
			(layer "F.SilkS")
		)
		(fp_line
			(start -0.7874 0.4064)
			(end -0.7874 -0.4064)
			(stroke
				(width 0.1524)
				(type default)
			)
			(layer "F.SilkS")
		)
		(fp_line
			(start -0.12065 -0.305054)
			(end -0.12065 -0.2794)
			(stroke
				(width 0.1)
				(type default)
			)
			(layer "F.Fab")
		)
		(fp_line
			(start -0.67945 -0.305054)
			(end -0.12065 -0.305054)
			(stroke
				(width 0.1)
				(type default)
			)
			(layer "F.Fab")
		)
		(fp_line
			(start 0.67945 -0.3048)
			(end 0.67945 0.3048)
			(stroke
				(width 0.1)
				(type default)
			)
			(layer "F.Fab")
		)
		(fp_line
			(start 0.12065 -0.3048)
			(end 0.67945 -0.3048)
			(stroke
				(width 0.1)
				(type default)
			)
			(layer "F.Fab")
		)
		(fp_line
			(start 0.12065 -0.2794)
			(end 0.12065 -0.3048)
			(stroke
				(width 0.1)
				(type default)
			)
			(layer "F.Fab")
		)
		(fp_line
			(start -0.12065 -0.2794)
			(end 0.12065 -0.2794)
			(stroke
				(width 0.1)
				(type default)
			)
			(layer "F.Fab")
		)
		(fp_line
			(start 0.120396 0.2794)
			(end -0.12065 0.2794)
			(stroke
				(width 0.1)
				(type default)
			)
			(layer "F.Fab")
		)
		(fp_line
			(start -0.12065 0.2794)
			(end -0.12065 0.3048)
			(stroke
				(width 0.1)
				(type default)
			)
			(layer "F.Fab")
		)
		(fp_line
			(start 0.67945 0.3048)
			(end 0.120396 0.3048)
			(stroke
				(width 0.1)
				(type default)
			)
			(layer "F.Fab")
		)
		(fp_line
			(start 0.120396 0.3048)
			(end 0.120396 0.2794)
			(stroke
				(width 0.1)
				(type default)
			)
			(layer "F.Fab")
		)
		(fp_line
			(start -0.12065 0.3048)
			(end -0.67945 0.3048)
			(stroke
				(width 0.1)
				(type default)
			)
			(layer "F.Fab")
		)
		(fp_line
			(start -0.67945 0.3048)
			(end -0.67945 -0.305054)
			(stroke
				(width 0.1)
				(type default)
			)
			(layer "F.Fab")
		)
		(pad "1" smd circle
			(at -0.40005 0 90)
			(size 0 0)
			(layers "F.Cu" "F.Mask" "F.Paste")
			(net "MB0_P12V_STBY_PWRGD")
		)
		(pad "2" smd circle
			(at 0.40005 0 90)
			(size 0 0)
			(layers "F.Cu" "F.Mask" "F.Paste")
			(net "FM_P12V_HSC_EN_R")
		)
	)
)
